# T6G (Grand Teton) — schematic netlist excerpt (pin names and nets, part order shuffled) for the footprints in the layout excerpt that follows; sources: Cadence DE-HDL packaged netlist, KiCad conversion of 04192023_DAF0TMB3IC0_F0TG_MB_C_brd_V02_OCP.brd

R4165  Q_RES  4.7K 5% CHIP  pkg 0402LF  page 124 : A = P3V3_AUX ; B = GPU_3V3IO_RSVD4_N
R164  Q_RES  33 5% CHIP  pkg 0402LF  page 80 : A = FM_I3C_CPU0_MUX0_R_SEL ; B = FM_I3C_CPU0_MUX0_SEL

(kicad_pcb
	(version 20260206)
	(generator "pcbnew")
	(generator_version "10.0")
	(general
		(thickness 1.6)
		(legacy_teardrops no)
	)
	(paper "A4")
	(title_block
		(title "04192023_DAF0TMB3IC0_F0TG_MB_C_brd_V02_OCP.brd")
		(comment 1 "Grand Teton / footprints 3187-3188 of 8354")
	)
	(layers
		(0 "F.Cu" signal "TOP")
		(4 "In1.Cu" signal "GND")
		(6 "In2.Cu" signal "IN1")
		(8 "In3.Cu" signal "GND1")
		(10 "In4.Cu" signal "IN2")
		(12 "In5.Cu" signal "GND2")
		(14 "In6.Cu" signal "IN3")
		(16 "In7.Cu" signal "GND3")
		(18 "In8.Cu" signal "VCC")
		(20 "In9.Cu" signal "VCC1")
		(22 "In10.Cu" signal "GND4")
		(24 "In11.Cu" signal "IN4")
		(26 "In12.Cu" signal "GND5")
		(28 "In13.Cu" signal "IN5")
		(30 "In14.Cu" signal "GND6")
		(32 "In15.Cu" signal "IN6")
		(34 "In16.Cu" signal "GND7")
		(2 "B.Cu" signal "BOTTOM")
		(9 "F.Adhes" user "F.Adhesive")
		(11 "B.Adhes" user "B.Adhesive")
		(13 "F.Paste" user "Package Geometry/Pastemask Top")
		(15 "B.Paste" user "Package Geometry/Pastemask Bottom")
		(5 "F.SilkS" user "Ref Des/Silkscreen Top")
		(7 "B.SilkS" user "Ref Des/Silkscreen Bottom")
		(1 "F.Mask" user "Board Geometry/Soldermask Top")
		(3 "B.Mask" user "Board Geometry/Soldermask Bottom")
		(17 "Dwgs.User" user "User.Drawings")
		(19 "Cmts.User" user "User.Comments")
		(21 "Eco1.User" user "User.Eco1")
		(23 "Eco2.User" user "User.Eco2")
		(25 "Edge.Cuts" user "Board Geometry/Outline")
		(27 "Margin" user)
		(31 "F.CrtYd" user "Package Geometry/Place Bound Top")
		(29 "B.CrtYd" user "Package Geometry/Place Bound Bottom")
		(35 "F.Fab" user "Ref Des/Assembly Top")
		(33 "B.Fab" user "Ref Des/Assembly Bottom")
	)
	(footprint ""
		(layer "F.Cu")
		(at 171.196 -106.136948 180)
		(property "Reference" "R164"
			(at 0 0 180)
			(layer "F.SilkS")
			(hide yes)
			(effects
				(font
					(size 1.27 1.27)
				)
			)
		)
		(property "Value" ""
			(at 0 0 180)
			(layer "F.Fab")
			(effects
				(font
					(size 1.27 1.27)
				)
			)
		)
		(duplicate_pad_numbers_are_jumpers no)
		(fp_line
			(start 0.7874 0.4064)
			(end -0.7874 0.4064)
			(stroke
				(width 0.1524)
				(type default)
			)
			(layer "F.SilkS")
		)
		(fp_line
			(start 0.7874 -0.4064)
			(end 0.7874 0.4064)
			(stroke
				(width 0.1524)
				(type default)
			)
			(layer "F.SilkS")
		)
		(fp_line
			(start -0.7874 0.4064)
			(end -0.7874 -0.4064)
			(stroke
				(width 0.1524)
				(type default)
			)
			(layer "F.SilkS")
		)
		(fp_line
			(start -0.7874 -0.4064)
			(end 0.7874 -0.4064)
			(stroke
				(width 0.1524)
				(type default)
			)
			(layer "F.SilkS")
		)
		(fp_line
			(start 0.67945 0.3048)
			(end 0.120396 0.3048)
			(stroke
				(width 0.1)
				(type default)
			)
			(layer "F.Fab")
		)
		(fp_line
			(start 0.67945 -0.3048)
			(end 0.67945 0.3048)
			(stroke
				(width 0.1)
				(type default)
			)
			(layer "F.Fab")
		)
		(fp_line
			(start 0.12065 -0.2794)
			(end 0.12065 -0.3048)
			(stroke
				(width 0.1)
				(type default)
			)
			(layer "F.Fab")
		)
		(fp_line
			(start 0.12065 -0.3048)
			(end 0.67945 -0.3048)
			(stroke
				(width 0.1)
				(type default)
			)
			(layer "F.Fab")
		)
		(fp_line
			(start 0.120396 0.3048)
			(end 0.120396 0.2794)
			(stroke
				(width 0.1)
				(type default)
			)
			(layer "F.Fab")
		)
		(fp_line
			(start 0.120396 0.2794)
			(end -0.12065 0.2794)
			(stroke
				(width 0.1)
				(type default)
			)
			(layer "F.Fab")
		)
		(fp_line
			(start -0.12065 0.3048)
			(end -0.67945 0.3048)
			(stroke
				(width 0.1)
				(type default)
			)
			(layer "F.Fab")
		)
		(fp_line
			(start -0.12065 0.2794)
			(end -0.12065 0.3048)
			(stroke
				(width 0.1)
				(type default)
			)
			(layer "F.Fab")
		)
		(fp_line
			(start -0.12065 -0.2794)
			(end 0.12065 -0.2794)
			(stroke
				(width 0.1)
				(type default)
			)
			(layer "F.Fab")
		)
		(fp_line
			(start -0.12065 -0.305054)
			(end -0.12065 -0.2794)
			(stroke
				(width 0.1)
				(type default)
			)
			(layer "F.Fab")
		)
		(fp_line
			(start -0.67945 0.3048)
			(end -0.67945 -0.305054)
			(stroke
				(width 0.1)
				(type default)
			)
			(layer "F.Fab")
		)
		(fp_line
			(start -0.67945 -0.305054)
			(end -0.12065 -0.305054)
			(stroke
				(width 0.1)
				(type default)
			)
			(layer "F.Fab")
		)
		(pad "1" smd circle
			(at -0.40005 0 180)
			(size 0 0)
			(layers "F.Cu" "F.Mask" "F.Paste")
			(net "FM_I3C_CPU0_MUX0_R_SEL")
		)
		(pad "2" smd circle
			(at 0.40005 0 180)
			(size 0 0)
			(layers "F.Cu" "F.Mask" "F.Paste")
			(net "FM_I3C_CPU0_MUX0_SEL")
		)
	)
	(footprint ""
		(layer "F.Cu")
		(at 444.36792 -437.428132 90)
		(property "Reference" "R4165"
			(at 0 0 90)
			(layer "F.SilkS")
			(hide yes)
			(effects
				(font
					(size 1.27 1.27)
				)
			)
		)
		(property "Value" ""
			(at 0 0 90)
			(layer "F.Fab")
			(effects
				(font
					(size 1.27 1.27)
				)
			)
		)
		(duplicate_pad_numbers_are_jumpers no)
		(fp_line
			(start 0.7874 -0.4064)
			(end 0.7874 0.4064)
			(stroke
				(width 0.1524)
				(type default)
			)
			(layer "F.SilkS")
		)
		(fp_line
			(start -0.7874 -0.4064)
			(end 0.7874 -0.4064)
			(stroke
				(width 0.1524)
				(type default)
			)
			(layer "F.SilkS")
		)
		(fp_line
			(start 0.7874 0.4064)
			(end -0.7874 0.4064)
			(stroke
				(width 0.1524)
				(type default)
			)
			(layer "F.SilkS")
		)
		(fp_line
			(start -0.7874 0.4064)
			(end -0.7874 -0.4064)
			(stroke
				(width 0.1524)
				(type default)
			)
			(layer "F.SilkS")
		)
		(fp_line
			(start -0.12065 -0.305054)
			(end -0.12065 -0.2794)
			(stroke
				(width 0.1)
				(type default)
			)
			(layer "F.Fab")
		)
		(fp_line
			(start -0.67945 -0.305054)
			(end -0.12065 -0.305054)
			(stroke
				(width 0.1)
				(type default)
			)
			(layer "F.Fab")
		)
		(fp_line
			(start 0.67945 -0.3048)
			(end 0.67945 0.3048)
			(stroke
				(width 0.1)
				(type default)
			)
			(layer "F.Fab")
		)
		(fp_line
			(start 0.12065 -0.3048)
			(end 0.67945 -0.3048)
			(stroke
				(width 0.1)
				(type default)
			)
			(layer "F.Fab")
		)
		(fp_line
			(start 0.12065 -0.2794)
			(end 0.12065 -0.3048)
			(stroke
				(width 0.1)
				(type default)
			)
			(layer "F.Fab")
		)
		(fp_line
			(start -0.12065 -0.2794)
			(end 0.12065 -0.2794)
			(stroke
				(width 0.1)
				(type default)
			)
			(layer "F.Fab")
		)
		(fp_line
			(start 0.120396 0.2794)
			(end -0.12065 0.2794)
			(stroke
				(width 0.1)
				(type default)
			)
			(layer "F.Fab")
		)
		(fp_line
			(start -0.12065 0.2794)
			(end -0.12065 0.3048)
			(stroke
				(width 0.1)
				(type default)
			)
			(layer "F.Fab")
		)
		(fp_line
			(start 0.67945 0.3048)
			(end 0.120396 0.3048)
			(stroke
				(width 0.1)
				(type default)
			)
			(layer "F.Fab")
		)
		(fp_line
			(start 0.120396 0.3048)
			(end 0.120396 0.2794)
			(stroke
				(width 0.1)
				(type default)
			)
			(layer "F.Fab")
		)
		(fp_line
			(start -0.12065 0.3048)
			(end -0.67945 0.3048)
			(stroke
				(width 0.1)
				(type default)
			)
			(layer "F.Fab")
		)
		(fp_line
			(start -0.67945 0.3048)
			(end -0.67945 -0.305054)
			(stroke
				(width 0.1)
				(type default)
			)
			(layer "F.Fab")
		)
		(pad "1" smd circle
			(at -0.40005 0 90)
			(size 0 0)
			(layers "F.Cu" "F.Mask" "F.Paste")
			(net "P3V3_AUX")
		)
		(pad "2" smd circle
			(at 0.40005 0 90)
			(size 0 0)
			(layers "F.Cu" "F.Mask" "F.Paste")
			(net "GPU_3V3IO_RSVD4_N")
		)
	)
)
